# S9S_MB_2U (Grand Teton) — schematic netlist excerpt (pin names and nets, part order shuffled) for the footprints in the layout excerpt that follows; sources: Cadence DE-HDL packaged netlist, KiCad conversion of 03242023_DA0F0TMBIJ0_F0T_Motherboard_J_brd_V01_OCP.brd

R1423  Q_RES  33.2 1% CHIP  pkg 0402LF  page 222 : A = PWRGD_SYS_PWROK_R ; B = PWRGD_SYS_PWROK
R42  Q_RES  10K 1% CHIP  pkg 0402LF  page 98 : A = PD_CHA_CPU1_DIMM1_SAA ; B = GND

(kicad_pcb
	(version 20260206)
	(generator "pcbnew")
	(generator_version "10.0")
	(general
		(thickness 1.6)
		(legacy_teardrops no)
	)
	(paper "A4")
	(title_block
		(title "03242023_DA0F0TMBIJ0_F0T_Motherboard_J_brd_V01_OCP.brd")
		(comment 1 "Grand Teton / footprints 4811-4812 of 6105")
	)
	(layers
		(0 "F.Cu" signal "TOP")
		(4 "In1.Cu" signal "GND")
		(6 "In2.Cu" signal "IN1")
		(8 "In3.Cu" signal "GND1")
		(10 "In4.Cu" signal "IN2")
		(12 "In5.Cu" signal "GND2")
		(14 "In6.Cu" signal "IN3")
		(16 "In7.Cu" signal "GND3")
		(18 "In8.Cu" signal "VCC")
		(20 "In9.Cu" signal "VCC1")
		(22 "In10.Cu" signal "GND4")
		(24 "In11.Cu" signal "IN4")
		(26 "In12.Cu" signal "GND5")
		(28 "In13.Cu" signal "IN5")
		(30 "In14.Cu" signal "GND6")
		(32 "In15.Cu" signal "IN6")
		(34 "In16.Cu" signal "GND7")
		(2 "B.Cu" signal "BOTTOM")
		(9 "F.Adhes" user "F.Adhesive")
		(11 "B.Adhes" user "B.Adhesive")
		(13 "F.Paste" user "Package Geometry/Pastemask Top")
		(15 "B.Paste" user "Package Geometry/Pastemask Bottom")
		(5 "F.SilkS" user "Ref Des/Silkscreen Top")
		(7 "B.SilkS" user "Ref Des/Silkscreen Bottom")
		(1 "F.Mask" user "Board Geometry/Soldermask Top")
		(3 "B.Mask" user "Board Geometry/Soldermask Bottom")
		(17 "Dwgs.User" user "User.Drawings")
		(19 "Cmts.User" user "User.Comments")
		(21 "Eco1.User" user "User.Eco1")
		(23 "Eco2.User" user "User.Eco2")
		(25 "Edge.Cuts" user "Board Geometry/Outline")
		(27 "Margin" user)
		(31 "F.CrtYd" user "Package Geometry/Place Bound Top")
		(29 "B.CrtYd" user "Package Geometry/Place Bound Bottom")
		(35 "F.Fab" user "Ref Des/Assembly Top")
		(33 "B.Fab" user "Ref Des/Assembly Bottom")
	)
	(footprint ""
		(layer "B.Cu")
		(at 318.323468 -35.170872 -135)
		(property "Reference" "R1423"
			(at 0 0 45)
			(layer "B.SilkS")
			(hide yes)
			(effects
				(font
					(size 1.27 1.27)
				)
				(justify mirror)
			)
		)
		(property "Value" ""
			(at 0 0 45)
			(layer "B.Fab")
			(effects
				(font
					(size 1.27 1.27)
				)
				(justify mirror)
			)
		)
		(duplicate_pad_numbers_are_jumpers no)
		(fp_line
			(start 0.787389 0.406267)
			(end 0.787389 -0.406267)
			(stroke
				(width 0.1524)
				(type default)
			)
			(layer "B.SilkS")
		)
		(fp_line
			(start 0.787389 -0.406267)
			(end -0.787389 -0.406267)
			(stroke
				(width 0.1524)
				(type default)
			)
			(layer "B.SilkS")
		)
		(fp_line
			(start -0.787389 0.406267)
			(end 0.787389 0.406267)
			(stroke
				(width 0.1524)
				(type default)
			)
			(layer "B.SilkS")
		)
		(fp_line
			(start -0.787389 -0.406267)
			(end -0.787389 0.406267)
			(stroke
				(width 0.1524)
				(type default)
			)
			(layer "B.SilkS")
		)
		(fp_line
			(start 0.679446 0.30479)
			(end 0.679446 -0.305149)
			(stroke
				(width 0.1)
				(type default)
			)
			(layer "B.Fab")
		)
		(fp_line
			(start 0.120515 0.30479)
			(end 0.679446 0.30479)
			(stroke
				(width 0.1)
				(type default)
			)
			(layer "B.Fab")
		)
		(fp_line
			(start 0.120695 0.279466)
			(end 0.120515 0.30479)
			(stroke
				(width 0.1)
				(type default)
			)
			(layer "B.Fab")
		)
		(fp_line
			(start 0.679446 -0.305149)
			(end 0.120695 -0.304969)
			(stroke
				(width 0.1)
				(type default)
			)
			(layer "B.Fab")
		)
		(fp_line
			(start -0.120515 0.30479)
			(end -0.120335 0.279466)
			(stroke
				(width 0.1)
				(type default)
			)
			(layer "B.Fab")
		)
		(fp_line
			(start -0.120335 0.279466)
			(end 0.120695 0.279466)
			(stroke
				(width 0.1)
				(type default)
			)
			(layer "B.Fab")
		)
		(fp_line
			(start 0.120695 -0.279466)
			(end -0.120695 -0.279466)
			(stroke
				(width 0.1)
				(type default)
			)
			(layer "B.Fab")
		)
		(fp_line
			(start 0.120695 -0.304969)
			(end 0.120695 -0.279466)
			(stroke
				(width 0.1)
				(type default)
			)
			(layer "B.Fab")
		)
		(fp_line
			(start -0.679446 0.30479)
			(end -0.120515 0.30479)
			(stroke
				(width 0.1)
				(type default)
			)
			(layer "B.Fab")
		)
		(fp_line
			(start -0.120695 -0.279466)
			(end -0.120515 -0.30479)
			(stroke
				(width 0.1)
				(type default)
			)
			(layer "B.Fab")
		)
		(fp_line
			(start -0.120515 -0.30479)
			(end -0.679446 -0.30479)
			(stroke
				(width 0.1)
				(type default)
			)
			(layer "B.Fab")
		)
		(fp_line
			(start -0.679446 -0.30479)
			(end -0.679446 0.30479)
			(stroke
				(width 0.1)
				(type default)
			)
			(layer "B.Fab")
		)
		(pad "1" smd circle
			(at 0.40005 0 45)
			(size 0 0)
			(layers "B.Cu" "B.Mask" "B.Paste")
			(net "PWRGD_SYS_PWROK_R")
		)
		(pad "2" smd circle
			(at -0.40005 0 45)
			(size 0 0)
			(layers "B.Cu" "B.Mask" "B.Paste")
			(net "PWRGD_SYS_PWROK")
		)
	)
	(footprint ""
		(layer "B.Cu")
		(at 55.280052 -319.009776)
		(property "Reference" "R42"
			(at 0 0 0)
			(layer "B.SilkS")
			(hide yes)
			(effects
				(font
					(size 1.27 1.27)
				)
				(justify mirror)
			)
		)
		(property "Value" ""
			(at 0 0 0)
			(layer "B.Fab")
			(effects
				(font
					(size 1.27 1.27)
				)
				(justify mirror)
			)
		)
		(duplicate_pad_numbers_are_jumpers no)
		(fp_line
			(start -0.7874 -0.4064)
			(end -0.7874 0.4064)
			(stroke
				(width 0.1524)
				(type default)
			)
			(layer "B.SilkS")
		)
		(fp_line
			(start -0.7874 0.4064)
			(end 0.7874 0.4064)
			(stroke
				(width 0.1524)
				(type default)
			)
			(layer "B.SilkS")
		)
		(fp_line
			(start 0.7874 -0.4064)
			(end -0.7874 -0.4064)
			(stroke
				(width 0.1524)
				(type default)
			)
			(layer "B.SilkS")
		)
		(fp_line
			(start 0.7874 0.4064)
			(end 0.7874 -0.4064)
			(stroke
				(width 0.1524)
				(type default)
			)
			(layer "B.SilkS")
		)
		(fp_line
			(start -0.67945 -0.3048)
			(end -0.67945 0.3048)
			(stroke
				(width 0.1)
				(type default)
			)
			(layer "B.Fab")
		)
		(fp_line
			(start -0.67945 0.3048)
			(end -0.120396 0.3048)
			(stroke
				(width 0.1)
				(type default)
			)
			(layer "B.Fab")
		)
		(fp_line
			(start -0.12065 -0.3048)
			(end -0.67945 -0.3048)
			(stroke
				(width 0.1)
				(type default)
			)
			(layer "B.Fab")
		)
		(fp_line
			(start -0.12065 -0.2794)
			(end -0.12065 -0.3048)
			(stroke
				(width 0.1)
				(type default)
			)
			(layer "B.Fab")
		)
		(fp_line
			(start -0.120396 0.2794)
			(end 0.12065 0.2794)
			(stroke
				(width 0.1)
				(type default)
			)
			(layer "B.Fab")
		)
		(fp_line
			(start -0.120396 0.3048)
			(end -0.120396 0.2794)
			(stroke
				(width 0.1)
				(type default)
			)
			(layer "B.Fab")
		)
		(fp_line
			(start 0.12065 -0.305054)
			(end 0.12065 -0.2794)
			(stroke
				(width 0.1)
				(type default)
			)
			(layer "B.Fab")
		)
		(fp_line
			(start 0.12065 -0.2794)
			(end -0.12065 -0.2794)
			(stroke
				(width 0.1)
				(type default)
			)
			(layer "B.Fab")
		)
		(fp_line
			(start 0.12065 0.2794)
			(end 0.12065 0.3048)
			(stroke
				(width 0.1)
				(type default)
			)
			(layer "B.Fab")
		)
		(fp_line
			(start 0.12065 0.3048)
			(end 0.67945 0.3048)
			(stroke
				(width 0.1)
				(type default)
			)
			(layer "B.Fab")
		)
		(fp_line
			(start 0.67945 -0.305054)
			(end 0.12065 -0.305054)
			(stroke
				(width 0.1)
				(type default)
			)
			(layer "B.Fab")
		)
		(fp_line
			(start 0.67945 0.3048)
			(end 0.67945 -0.305054)
			(stroke
				(width 0.1)
				(type default)
			)
			(layer "B.Fab")
		)
		(pad "1" smd circle
			(at 0.40005 0 180)
			(size 0 0)
			(layers "B.Cu" "B.Mask" "B.Paste")
			(net "PD_CHA_CPU1_DIMM1_SAA")
		)
		(pad "2" smd circle
			(at -0.40005 0 180)
			(size 0 0)
			(layers "B.Cu" "B.Mask" "B.Paste")
			(net "GND")
		)
	)
)
